FILE_TYPE=LIBRARY_PARTS;
primitive 'MOSFET_NCH_GDS_ESD_PROTECTED';
  pin
    'D':
      PIN_NUMBER='(D)';
      BIDIRECTIONAL='TRUE';
      INPUT_LOAD='(-0.01,0.01)';
      OUTPUT_LOAD='(1.0,-1.0)';
    'G':
      PIN_NUMBER='(G)';
      INPUT_LOAD='(-0.01,0.01)';
    'S':
      PIN_NUMBER='(S)';
      BIDIRECTIONAL='TRUE';
      INPUT_LOAD='(-0.01,0.01)';
      OUTPUT_LOAD='(1.0,-1.0)';
  end_pin;
  body
    PART_NAME='MOSFET_NCH_GDS_ESD_PROTECTED';
    BODY_NAME='MOSFET_NCH_GDS_ESD_PROTECTED';
    PHYS_DES_PREFIX='U';
    CLASS='IC';
  end_body;
end_primitive;

END.
